(kicad_pcb
	(version 20260206)
	(generator "pcbnew")
	(generator_version "10.0")
	(general
		(thickness 1.6)
		(legacy_teardrops no)
	)
	(paper "A4")
	(title_block
		(title "ptb — 12523-1.1018WZS1506.brd")
		(comment 1 "Open Vault / Knox (Wiwynn) / footprint 34 of 61 (CN4), pads 1-54 of 54")
	)
	(layers
		(0 "F.Cu" signal "TOP")
		(4 "In1.Cu" signal "L2GND")
		(6 "In2.Cu" signal "L3VCC")
		(2 "B.Cu" signal "BOTTOM")
		(9 "F.Adhes" user "F.Adhesive")
		(11 "B.Adhes" user "B.Adhesive")
		(13 "F.Paste" user "Package Geometry/Pastemask Top")
		(15 "B.Paste" user "Package Geometry/Pastemask Bottom")
		(5 "F.SilkS" user "Ref Des/Silkscreen Top")
		(7 "B.SilkS" user "Ref Des/Silkscreen Bottom")
		(1 "F.Mask" user "Board Geometry/Soldermask Top")
		(3 "B.Mask" user "Board Geometry/Soldermask Bottom")
		(17 "Dwgs.User" user "User.Drawings")
		(19 "Cmts.User" user "User.Comments")
		(21 "Eco1.User" user "User.Eco1")
		(23 "Eco2.User" user "User.Eco2")
		(25 "Edge.Cuts" user "Board Geometry/Outline")
		(27 "Margin" user)
		(31 "F.CrtYd" user "Package Geometry/Place Bound Top")
		(29 "B.CrtYd" user "Package Geometry/Place Bound Bottom")
		(35 "F.Fab" user "Ref Des/Assembly Top")
		(33 "B.Fab" user "Ref Des/Assembly Bottom")
	)
	(footprint ""
		(layer "F.Cu")
		(at 152.580086 -56.999886 90)
		(property "Reference" "CN4"
			(at 0 0 90)
			(layer "F.SilkS")
			(hide yes)
			(effects
				(font
					(size 1.27 1.27)
				)
			)
		)
		(property "Value" "FCI-CONN52-4R-GP"
			(at -28.321 -4.0132 90)
			(unlocked yes)
			(layer "F.Fab")
			(hide yes)
			(effects
				(font
					(size 1.016 1.016)
					(thickness 0.1524)
				)
			)
		)
		(property "Device Type" "51939-689LF"
			(at -28.321 -5.5372 90)
			(unlocked yes)
			(layer "F.Fab")
			(hide yes)
			(effects
				(font
					(size 1.016 1.016)
					(thickness 0.1524)
				)
			)
		)
		(duplicate_pad_numbers_are_jumpers no)
		(pad "" np_thru_hole circle
			(at -22.225 0 90)
			(size 0.254 0.254)
			(drill 4.0132)
			(layers "*.Cu" "*.Mask")
			(clearance 2.2352)
			(thermal_gap 2.2352)
		)
		(pad "" np_thru_hole circle
			(at 22.225 0 90)
			(size 0.254 0.254)
			(drill 4.0132)
			(layers "*.Cu" "*.Mask")
			(clearance 2.2352)
			(thermal_gap 2.2352)
		)
		(pad "A1" thru_hole circle
			(at -5.08 0 90)
			(size 1.4478 1.4478)
			(drill 1.0414)
			(layers "*.Cu" "*.Mask")
			(remove_unused_layers no)
			(net "I2C_C_BUF_SDA_CONN")
			(clearance 0.1524)
			(thermal_gap 0.1524)
		)
		(pad "A2" thru_hole circle
			(at -2.54 0 90)
			(size 1.4478 1.4478)
			(drill 1.0414)
			(layers "*.Cu" "*.Mask")
			(remove_unused_layers no)
			(net "GND")
			(clearance 0.1524)
			(thermal_gap 0.1524)
		)
		(pad "A3" thru_hole circle
			(at 0 0 90)
			(size 1.4478 1.4478)
			(drill 1.0414)
			(layers "*.Cu" "*.Mask")
			(remove_unused_layers no)
			(net "I2C_C_BUF_SCL_CONN")
			(clearance 0.1524)
			(thermal_gap 0.1524)
		)
		(pad "A4" thru_hole circle
			(at 2.54 0 90)
			(size 1.4478 1.4478)
			(drill 1.0414)
			(layers "*.Cu" "*.Mask")
			(remove_unused_layers no)
			(net "GND")
			(clearance 0.1524)
			(thermal_gap 0.1524)
		)
		(pad "A5" thru_hole circle
			(at 5.08 0 90)
			(size 1.4478 1.4478)
			(drill 1.0414)
			(layers "*.Cu" "*.Mask")
			(remove_unused_layers no)
			(net "PWM_EXP_B_OUT")
			(clearance 0.1524)
			(thermal_gap 0.1524)
		)
		(pad "B1" thru_hole circle
			(at -5.08 -2.54 90)
			(size 1.4478 1.4478)
			(drill 1.0414)
			(layers "*.Cu" "*.Mask")
			(remove_unused_layers no)
			(net "GND")
			(clearance 0.1524)
			(thermal_gap 0.1524)
		)
		(pad "B2" thru_hole circle
			(at -2.54 -2.54 90)
			(size 1.4478 1.4478)
			(drill 1.0414)
			(layers "*.Cu" "*.Mask")
			(remove_unused_layers no)
			(net "PWM_EXP_A_OUT")
			(clearance 0.1524)
			(thermal_gap 0.1524)
		)
		(pad "B3" thru_hole circle
			(at 0 -2.54 90)
			(size 1.4478 1.4478)
			(drill 1.0414)
			(layers "*.Cu" "*.Mask")
			(remove_unused_layers no)
			(net "GND")
			(clearance 0.1524)
			(thermal_gap 0.1524)
		)
		(pad "B4" thru_hole circle
			(at 2.54 -2.54 90)
			(size 1.4478 1.4478)
			(drill 1.0414)
			(layers "*.Cu" "*.Mask")
			(remove_unused_layers no)
			(net "SELF_1B&2B_HB")
			(clearance 0.1524)
			(thermal_gap 0.1524)
		)
		(pad "B5" thru_hole circle
			(at 5.08 -2.54 90)
			(size 1.4478 1.4478)
			(drill 1.0414)
			(layers "*.Cu" "*.Mask")
			(remove_unused_layers no)
			(net "GND")
			(clearance 0.1524)
			(thermal_gap 0.1524)
		)
		(pad "C1" thru_hole circle
			(at -5.08 -5.08 90)
			(size 1.4478 1.4478)
			(drill 1.0414)
			(layers "*.Cu" "*.Mask")
			(remove_unused_layers no)
			(net "TPS2490_EN1")
			(clearance 0.1524)
			(thermal_gap 0.1524)
		)
		(pad "C2" thru_hole circle
			(at -2.54 -5.08 90)
			(size 1.4478 1.4478)
			(drill 1.0414)
			(layers "*.Cu" "*.Mask")
			(remove_unused_layers no)
			(net "TPS2490_EN2")
			(clearance 0.1524)
			(thermal_gap 0.1524)
		)
		(pad "C3" thru_hole circle
			(at 0 -5.08 90)
			(size 1.4478 1.4478)
			(drill 1.0414)
			(layers "*.Cu" "*.Mask")
			(remove_unused_layers no)
			(net "SELF_1A&2A_HB")
			(clearance 0.1524)
			(thermal_gap 0.1524)
		)
		(pad "C4" thru_hole circle
			(at 2.54 -5.08 90)
			(size 1.4478 1.4478)
			(drill 1.0414)
			(layers "*.Cu" "*.Mask")
			(remove_unused_layers no)
			(net "PEER_1A&2A_HB")
			(clearance 0.1524)
			(thermal_gap 0.1524)
		)
		(pad "C5" thru_hole circle
			(at 5.08 -5.08 90)
			(size 1.4478 1.4478)
			(drill 1.0414)
			(layers "*.Cu" "*.Mask")
			(remove_unused_layers no)
			(net "PEER_1B&2B_HB")
			(clearance 0.1524)
			(thermal_gap 0.1524)
		)
		(pad "D1" thru_hole circle
			(at -5.08 -7.62 90)
			(size 1.4478 1.4478)
			(drill 1.0414)
			(layers "*.Cu" "*.Mask")
			(remove_unused_layers no)
			(net "PEER_TRAY_PRESENT")
			(clearance 0.1524)
			(thermal_gap 0.1524)
		)
		(pad "D2" thru_hole circle
			(at -2.54 -7.62 90)
			(size 1.4478 1.4478)
			(drill 1.0414)
			(layers "*.Cu" "*.Mask")
			(remove_unused_layers no)
			(net "TRAY_ID")
			(clearance 0.1524)
			(thermal_gap 0.1524)
		)
		(pad "D3" thru_hole circle
			(at 0 -7.62 90)
			(size 1.4478 1.4478)
			(drill 1.0414)
			(layers "*.Cu" "*.Mask")
			(remove_unused_layers no)
			(net "FCB_HW_REV")
			(clearance 0.1524)
			(thermal_gap 0.1524)
		)
		(pad "D4" thru_hole circle
			(at 2.54 -7.62 90)
			(size 1.4478 1.4478)
			(drill 1.0414)
			(layers "*.Cu" "*.Mask")
			(remove_unused_layers no)
			(net "SD_LATCH_RELEASE")
			(clearance 0.1524)
			(thermal_gap 0.1524)
		)
		(pad "D5" thru_hole circle
			(at 5.08 -7.62 90)
			(size 1.4478 1.4478)
			(drill 1.0414)
			(layers "*.Cu" "*.Mask")
			(remove_unused_layers no)
			(net "SELF_TRAY_PRESENT")
			(clearance 0.1524)
			(thermal_gap 0.1524)
		)
		(pad "P1_1" thru_hole circle
			(at -15.88008 0 90)
			(size 1.4478 1.4478)
			(drill 1.0414)
			(layers "*.Cu" "*.Mask")
			(remove_unused_layers no)
			(net "P12V")
			(clearance 0.1524)
			(thermal_gap 0.1524)
		)
		(pad "P1_2" thru_hole circle
			(at -15.88008 -2.54 90)
			(size 1.4478 1.4478)
			(drill 1.0414)
			(layers "*.Cu" "*.Mask")
			(remove_unused_layers no)
			(net "P12V")
			(clearance 0.1524)
			(thermal_gap 0.1524)
		)
		(pad "P1_3" thru_hole circle
			(at -15.88008 -5.08 90)
			(size 1.4478 1.4478)
			(drill 1.0414)
			(layers "*.Cu" "*.Mask")
			(remove_unused_layers no)
			(net "P12V")
			(clearance 0.1524)
			(thermal_gap 0.1524)
		)
		(pad "P1_4" thru_hole circle
			(at -15.88008 -7.62 90)
			(size 1.4478 1.4478)
			(drill 1.0414)
			(layers "*.Cu" "*.Mask")
			(remove_unused_layers no)
			(net "P12V")
			(clearance 0.1524)
			(thermal_gap 0.1524)
		)
		(pad "P1_5" thru_hole circle
			(at -13.34008 0 90)
			(size 1.4478 1.4478)
			(drill 1.0414)
			(layers "*.Cu" "*.Mask")
			(remove_unused_layers no)
			(net "P12V")
			(clearance 0.1524)
			(thermal_gap 0.1524)
		)
		(pad "P1_6" thru_hole circle
			(at -13.34008 -2.54 90)
			(size 1.4478 1.4478)
			(drill 1.0414)
			(layers "*.Cu" "*.Mask")
			(remove_unused_layers no)
			(net "P12V")
			(clearance 0.1524)
			(thermal_gap 0.1524)
		)
		(pad "P1_7" thru_hole circle
			(at -13.34008 -5.08 90)
			(size 1.4478 1.4478)
			(drill 1.0414)
			(layers "*.Cu" "*.Mask")
			(remove_unused_layers no)
			(net "P12V")
			(clearance 0.1524)
			(thermal_gap 0.1524)
		)
		(pad "P1_8" thru_hole circle
			(at -13.34008 -7.62 90)
			(size 1.4478 1.4478)
			(drill 1.0414)
			(layers "*.Cu" "*.Mask")
			(remove_unused_layers no)
			(net "P12V")
			(clearance 0.1524)
			(thermal_gap 0.1524)
		)
		(pad "P2_1" thru_hole circle
			(at -10.80008 0 90)
			(size 1.4478 1.4478)
			(drill 1.0414)
			(layers "*.Cu" "*.Mask")
			(remove_unused_layers no)
			(net "P12V")
			(clearance 0.1524)
			(thermal_gap 0.1524)
		)
		(pad "P2_2" thru_hole circle
			(at -10.80008 -2.54 90)
			(size 1.4478 1.4478)
			(drill 1.0414)
			(layers "*.Cu" "*.Mask")
			(remove_unused_layers no)
			(net "P12V")
			(clearance 0.1524)
			(thermal_gap 0.1524)
		)
		(pad "P2_3" thru_hole circle
			(at -10.80008 -5.08 90)
			(size 1.4478 1.4478)
			(drill 1.0414)
			(layers "*.Cu" "*.Mask")
			(remove_unused_layers no)
			(net "P12V")
			(clearance 0.1524)
			(thermal_gap 0.1524)
		)
		(pad "P2_4" thru_hole circle
			(at -10.80008 -7.62 90)
			(size 1.4478 1.4478)
			(drill 1.0414)
			(layers "*.Cu" "*.Mask")
			(remove_unused_layers no)
			(net "P12V")
			(clearance 0.1524)
			(thermal_gap 0.1524)
		)
		(pad "P2_5" thru_hole circle
			(at -8.26008 0 90)
			(size 1.4478 1.4478)
			(drill 1.0414)
			(layers "*.Cu" "*.Mask")
			(remove_unused_layers no)
			(net "P12V")
			(clearance 0.1524)
			(thermal_gap 0.1524)
		)
		(pad "P2_6" thru_hole circle
			(at -8.26008 -2.54 90)
			(size 1.4478 1.4478)
			(drill 1.0414)
			(layers "*.Cu" "*.Mask")
			(remove_unused_layers no)
			(net "P12V")
			(clearance 0.1524)
			(thermal_gap 0.1524)
		)
		(pad "P2_7" thru_hole circle
			(at -8.26008 -5.08 90)
			(size 1.4478 1.4478)
			(drill 1.0414)
			(layers "*.Cu" "*.Mask")
			(remove_unused_layers no)
			(net "P12V")
			(clearance 0.1524)
			(thermal_gap 0.1524)
		)
		(pad "P2_8" thru_hole circle
			(at -8.26008 -7.62 90)
			(size 1.4478 1.4478)
			(drill 1.0414)
			(layers "*.Cu" "*.Mask")
			(remove_unused_layers no)
			(net "P12V")
			(clearance 0.1524)
			(thermal_gap 0.1524)
		)
		(pad "P3_1" thru_hole circle
			(at 8.26008 0 90)
			(size 1.4478 1.4478)
			(drill 1.0414)
			(layers "*.Cu" "*.Mask")
			(remove_unused_layers no)
			(net "GND")
			(clearance 0.1524)
			(thermal_gap 0.1524)
		)
		(pad "P3_2" thru_hole circle
			(at 8.26008 -2.54 90)
			(size 1.4478 1.4478)
			(drill 1.0414)
			(layers "*.Cu" "*.Mask")
			(remove_unused_layers no)
			(net "GND")
			(clearance 0.1524)
			(thermal_gap 0.1524)
		)
		(pad "P3_3" thru_hole circle
			(at 8.26008 -5.08 90)
			(size 1.4478 1.4478)
			(drill 1.0414)
			(layers "*.Cu" "*.Mask")
			(remove_unused_layers no)
			(net "GND")
			(clearance 0.1524)
			(thermal_gap 0.1524)
		)
		(pad "P3_4" thru_hole circle
			(at 8.26008 -7.62 90)
			(size 1.4478 1.4478)
			(drill 1.0414)
			(layers "*.Cu" "*.Mask")
			(remove_unused_layers no)
			(net "GND")
			(clearance 0.1524)
			(thermal_gap 0.1524)
		)
		(pad "P3_5" thru_hole circle
			(at 10.80008 0 90)
			(size 1.4478 1.4478)
			(drill 1.0414)
			(layers "*.Cu" "*.Mask")
			(remove_unused_layers no)
			(net "GND")
			(clearance 0.1524)
			(thermal_gap 0.1524)
		)
		(pad "P3_6" thru_hole circle
			(at 10.80008 -2.54 90)
			(size 1.4478 1.4478)
			(drill 1.0414)
			(layers "*.Cu" "*.Mask")
			(remove_unused_layers no)
			(net "GND")
			(clearance 0.1524)
			(thermal_gap 0.1524)
		)
		(pad "P3_7" thru_hole circle
			(at 10.80008 -5.08 90)
			(size 1.4478 1.4478)
			(drill 1.0414)
			(layers "*.Cu" "*.Mask")
			(remove_unused_layers no)
			(net "GND")
			(clearance 0.1524)
			(thermal_gap 0.1524)
		)
		(pad "P3_8" thru_hole circle
			(at 10.80008 -7.62 90)
			(size 1.4478 1.4478)
			(drill 1.0414)
			(layers "*.Cu" "*.Mask")
			(remove_unused_layers no)
			(net "GND")
			(clearance 0.1524)
			(thermal_gap 0.1524)
		)
		(pad "P4_1" thru_hole circle
			(at 13.34008 0 90)
			(size 1.4478 1.4478)
			(drill 1.0414)
			(layers "*.Cu" "*.Mask")
			(remove_unused_layers no)
			(net "GND")
			(clearance 0.1524)
			(thermal_gap 0.1524)
		)
		(pad "P4_2" thru_hole circle
			(at 13.34008 -2.54 90)
			(size 1.4478 1.4478)
			(drill 1.0414)
			(layers "*.Cu" "*.Mask")
			(remove_unused_layers no)
			(net "GND")
			(clearance 0.1524)
			(thermal_gap 0.1524)
		)
		(pad "P4_3" thru_hole circle
			(at 13.34008 -5.08 90)
			(size 1.4478 1.4478)
			(drill 1.0414)
			(layers "*.Cu" "*.Mask")
			(remove_unused_layers no)
			(net "GND")
			(clearance 0.1524)
			(thermal_gap 0.1524)
		)
		(pad "P4_4" thru_hole circle
			(at 13.34008 -7.62 90)
			(size 1.4478 1.4478)
			(drill 1.0414)
			(layers "*.Cu" "*.Mask")
			(remove_unused_layers no)
			(net "GND")
			(clearance 0.1524)
			(thermal_gap 0.1524)
		)
		(pad "P4_5" thru_hole circle
			(at 15.88008 0 90)
			(size 1.4478 1.4478)
			(drill 1.0414)
			(layers "*.Cu" "*.Mask")
			(remove_unused_layers no)
			(net "GND")
			(clearance 0.1524)
			(thermal_gap 0.1524)
		)
		(pad "P4_6" thru_hole circle
			(at 15.88008 -2.54 90)
			(size 1.4478 1.4478)
			(drill 1.0414)
			(layers "*.Cu" "*.Mask")
			(remove_unused_layers no)
			(net "GND")
			(clearance 0.1524)
			(thermal_gap 0.1524)
		)
		(pad "P4_7" thru_hole circle
			(at 15.88008 -5.08 90)
			(size 1.4478 1.4478)
			(drill 1.0414)
			(layers "*.Cu" "*.Mask")
			(remove_unused_layers no)
			(net "GND")
			(clearance 0.1524)
			(thermal_gap 0.1524)
		)
		(pad "P4_8" thru_hole circle
			(at 15.88008 -7.62 90)
			(size 1.4478 1.4478)
			(drill 1.0414)
			(layers "*.Cu" "*.Mask")
			(remove_unused_layers no)
			(net "GND")
			(clearance 0.1524)
			(thermal_gap 0.1524)
		)
	)
)
